FILE_TYPE = CONNECTIVITY;
{Allegro Design Entry HDL 16.6-p007 (v16-6-112F) 10/10/2012}
"PAGE_NUMBER" = 63;
0"NC";
1"PVCCMCP_CPU1\g";
2"TP_CPU1_DMI_TX_DP0";
3"TP_CPU1_DMI_TX_DP2";
4"TP_CPU1_RSVD_172";
5"TP_CPU1_DMI_RX_DP0";
6"TP_CPU1_DMI_RX_DP3";
7"TP_CPU1_DMI_RX_DP1";
8"TP_CPU1_DMI_RX_DN3";
9"TP_CPU1_DMI_RX_DN0";
10"TP_IRQ_CPU1_CD_HFI0_N";
11"JTAG_MCP_TCK";
12"JTAG_MCP_CPU1_TDI";
13"JTAG_MCP_TMS";
14"JTAG_MCP_TRST_N";
15"TP_CPU1_RSVD_183";
16"TP_CPU1_RSVD_180";
17"TP_CPU1_RSVD_179";
18"TP_CPU1_RSVD_177";
19"TP_CPU1_RSVD_175";
20"TP_CPU1_RSVD_174";
21"TP_CPU1_RSVD_176";
22"TP_CPU1_RSVD_182";
23"TP_CPU1_RSVD_178";
24"TP_CPU1_RSVD_181";
25"CLK_156M_OSC_CPU1_HFI_DP";
26"CLK_156M_OSC_CPU1_HFI_DN";
27"TP_CPU1_DMI_RX_DN1";
28"TP_CPU1_DMI_RX_DN2";
29"TP_CPU1_DMI_RX_DP2";
30"TP_SMB_CPU1_CD_HFI0_I2CDAT";
31"TP_SMB_CPU1_CD_HFI0_I2CCLK";
32"TP_LED_CPU1_CD_HFI0_N";
33"TP_RST_CPU1_CD_HFI0_N";
34"TP_FM_CPU1_CD_HFI0_MODPRST_N";
35"TP_CPU1_RSVD_173";
36"TP_CPU1_RSVD_184";
37"TP_CPU1_RSVD_186";
38"TP_CPU1_RSVD_189";
39"TP_CPU1_RSVD_190";
40"JTAG_MCP_CPU1_TDO";
41"RST_CD_CPU1_POR_N";
42"TP_CD_HFI1_CPU1_I2CDAT";
43"TP_CD_HFI1_CPU1_I2CLK";
44"TP_CD_HFI1_CPU1_INT_N";
45"TP_CD_HFI1_CPU1_LED_N";
46"TP_CD_HFI1_CPU1_MODPRST_N";
47"TP_CD_HFI1_CPU1_RESET_N";
48"CLK_100M_CPU1_PE_REFCLK_DP";
49"CLK_100M_CPU1_PE_REFCLK_DN";
50"TP_CPU1_DMI_TX_DP3";
51"TP_CPU1_DMI_TX_DP1";
52"TP_CPU1_DMI_TX_DN3";
53"TP_CPU1_DMI_TX_DN2";
54"TP_CPU1_DMI_TX_DN1";
55"TP_CPU1_DMI_TX_DN0";
%"SKX_EXT_B"
"9","(-4075,2500)","0","chpset_lib","I23";
;
CDS_SEC"9"
LOCATION"U2D1"
PART_NUMBER"TBD"
MATERIAL"IC"
PACK_TYPE"BGA1"
SEC_TYPE"BGA1"
CDS_LIB"chpset_lib"
SEC"9"
CDS_LOCATION"U2D1";
"RSVD<172>"
$PN"BA76"4;
"RSVD<173>"
$PN"BA66"35;
"RSVD<174>"
$PN"BA64"20;
"RSVD<175>"
$PN"BA22"19;
"RSVD<176>"
$PN"BA18"21;
"RSVD<177>"
$PN"BA16"18;
"RSVD<178>"
$PN"BA14"23;
"RSVD<179>"
$PN"AY77"17;
"RSVD<180>"
$PN"AY75"16;
"RSVD<181>"
$PN"AY67"24;
"RSVD<182>"
$PN"AY65"22;
"RSVD<183>"
$PN"AW76"15;
"RSVD<184>"
$PN"AW64"36;
"RSVD<186>"
$PN"AV77"37;
"RSVD<187>"
$PN"AT25"1;
"RSVD<188>"
$PN"AT23"1;
"RSVD<189>"
$PN"AT13"38;
"RSVD<190>"
$PN"AR62"39;
"RSVD<191>"
$PN"AR26"1;
"RSVD<192>"
$PN"AR22"1;
"RSVD<193>"
$PN"AR20"1;
"DMI_TX_DP<0>"
$PN"CH5"2;
"DMI_TX_DP<1>"
$PN"CL4"51;
"DMI_TX_DP<2>"
$PN"CM3"3;
"DMI_TX_DP<3>"
$PN"CR4"50;
"DMI_TX_DN<0>"
$PN"CG4"55;
"DMI_TX_DN<1>"
$PN"CJ4"54;
"DMI_TX_DN<2>"
$PN"CN4"53;
"DMI_TX_DN<3>"
$PN"CP5"52;
"DMI_RX_DP<0>"
$PN"CL10"5;
"DMI_RX_DP<1>"
$PN"CN10"7;
"DMI_RX_DP<2>"
$PN"CP11"29;
"DMI_RX_DP<3>"
$PN"CV11"6;
"DMI_RX_DN<0>"
$PN"CK9"9;
"DMI_RX_DN<1>"
$PN"CM11"27;
"DMI_RX_DN<2>"
$PN"CR12"28;
"DMI_RX_DN<3>"
$PN"CT11"8;
"CD_TRST_N"
$PN"CD23"14;
"CD_TMS"
$PN"CE24"13;
"CD_TDO"
$PN"CC22"40;
"CD_TDI"
$PN"BY21"12;
"CD_TCLK"
$PN"CB23"11;
"CD_POR_N"
$PN"CF25"41;
"CD_PE_REFCLK_DP"
$PN"BW24"48;
"CD_PE_REFCLK_DN"
$PN"BU24"49;
"CD_HFI_REFCLK_DP"
$PN"BG16"25;
"CD_HFI_REFCLK_DN"
$PN"BE16"26;
"CD_HFI1_RESET_N"
$PN"BK23"47;
"CD_HFI1_MODPRST_N"
$PN"BT19"46;
"CD_HFI1_LED_N"
$PN"BM23"45;
"CD_HFI1_INT_N"
$PN"BM21"44;
"CD_HFI1_I2CDAT"
$PN"BH23"42;
"CD_HFI1_I2CCLK"
$PN"BJ22"43;
"CD_HFI0_RESET_N"
$PN"BN24"33;
"CD_HFI0_MODPRST_N"
$PN"BR20"34;
"CD_HFI0_LED_N"
$PN"BK21"32;
"CD_HFI0_INT_N"
$PN"BP19"10;
"CD_HFI0_I2CDAT"
$PN"BP23"30;
"CD_HFI0_I2CCLK"
$PN"BN22"31;
%"VCC_CORE"
"1","(-1425,2250)","0","mstr_symbols","I27";
;
HDL_POWER"PVCCMCP_CPU1"
CDS_LIB"mstr_symbols";
"A"1;
END.
